(kicad_pcb
	(version 20260206)
	(generator "pcbnew")
	(generator_version "10.0")
	(general
		(thickness 1.6)
		(legacy_teardrops no)
	)
	(paper "A4")
	(title_block
		(title "04192023_DAF0TMB3IC0_F0TG_MB_C_brd_V02_OCP.brd")
		(comment 1 "Grand Teton / footprints 886-893 of 8354")
	)
	(layers
		(0 "F.Cu" signal "TOP")
		(4 "In1.Cu" signal "GND")
		(6 "In2.Cu" signal "IN1")
		(8 "In3.Cu" signal "GND1")
		(10 "In4.Cu" signal "IN2")
		(12 "In5.Cu" signal "GND2")
		(14 "In6.Cu" signal "IN3")
		(16 "In7.Cu" signal "GND3")
		(18 "In8.Cu" signal "VCC")
		(20 "In9.Cu" signal "VCC1")
		(22 "In10.Cu" signal "GND4")
		(24 "In11.Cu" signal "IN4")
		(26 "In12.Cu" signal "GND5")
		(28 "In13.Cu" signal "IN5")
		(30 "In14.Cu" signal "GND6")
		(32 "In15.Cu" signal "IN6")
		(34 "In16.Cu" signal "GND7")
		(2 "B.Cu" signal "BOTTOM")
		(9 "F.Adhes" user "F.Adhesive")
		(11 "B.Adhes" user "B.Adhesive")
		(13 "F.Paste" user "Package Geometry/Pastemask Top")
		(15 "B.Paste" user "Package Geometry/Pastemask Bottom")
		(5 "F.SilkS" user "Ref Des/Silkscreen Top")
		(7 "B.SilkS" user "Ref Des/Silkscreen Bottom")
		(1 "F.Mask" user "Board Geometry/Soldermask Top")
		(3 "B.Mask" user "Board Geometry/Soldermask Bottom")
		(17 "Dwgs.User" user "User.Drawings")
		(19 "Cmts.User" user "User.Comments")
		(21 "Eco1.User" user "User.Eco1")
		(23 "Eco2.User" user "User.Eco2")
		(25 "Edge.Cuts" user "Board Geometry/Outline")
		(27 "Margin" user)
		(31 "F.CrtYd" user "Package Geometry/Place Bound Top")
		(29 "B.CrtYd" user "Package Geometry/Place Bound Bottom")
		(35 "F.Fab" user "Ref Des/Assembly Top")
		(33 "B.Fab" user "Ref Des/Assembly Bottom")
	)
	(footprint ""
		(layer "F.Cu")
		(at 140.02512 -30.82671 90)
		(property "Reference" "C6018"
			(at 0 0 90)
			(layer "F.SilkS")
			(hide yes)
			(effects
				(font
					(size 1.27 1.27)
				)
			)
		)
		(property "Value" ""
			(at 0 0 90)
			(layer "F.Fab")
			(effects
				(font
					(size 1.27 1.27)
				)
			)
		)
		(duplicate_pad_numbers_are_jumpers no)
		(fp_line
			(start 0.7874 -0.4064)
			(end 0.7874 0.4064)
			(stroke
				(width 0.1524)
				(type default)
			)
			(layer "F.SilkS")
		)
		(fp_line
			(start -0.7874 -0.4064)
			(end 0.7874 -0.4064)
			(stroke
				(width 0.1524)
				(type default)
			)
			(layer "F.SilkS")
		)
		(fp_line
			(start 0.7874 0.4064)
			(end -0.7874 0.4064)
			(stroke
				(width 0.1524)
				(type default)
			)
			(layer "F.SilkS")
		)
		(fp_line
			(start -0.7874 0.4064)
			(end -0.7874 -0.4064)
			(stroke
				(width 0.1524)
				(type default)
			)
			(layer "F.SilkS")
		)
		(fp_line
			(start 0.6858 -0.3048)
			(end 0.6858 0.3048)
			(stroke
				(width 0.1)
				(type default)
			)
			(layer "F.Fab")
		)
		(fp_line
			(start 0.1016 -0.3048)
			(end 0.6858 -0.3048)
			(stroke
				(width 0.1)
				(type default)
			)
			(layer "F.Fab")
		)
		(fp_line
			(start -0.1016 -0.3048)
			(end -0.1016 -0.2794)
			(stroke
				(width 0.1)
				(type default)
			)
			(layer "F.Fab")
		)
		(fp_line
			(start -0.6858 -0.3048)
			(end -0.1016 -0.3048)
			(stroke
				(width 0.1)
				(type default)
			)
			(layer "F.Fab")
		)
		(fp_line
			(start 0.1016 -0.2794)
			(end 0.1016 -0.3048)
			(stroke
				(width 0.1)
				(type default)
			)
			(layer "F.Fab")
		)
		(fp_line
			(start -0.1016 -0.2794)
			(end 0.1016 -0.2794)
			(stroke
				(width 0.1)
				(type default)
			)
			(layer "F.Fab")
		)
		(fp_line
			(start 0.1016 0.2794)
			(end -0.1016 0.2794)
			(stroke
				(width 0.1)
				(type default)
			)
			(layer "F.Fab")
		)
		(fp_line
			(start -0.1016 0.2794)
			(end -0.1016 0.3048)
			(stroke
				(width 0.1)
				(type default)
			)
			(layer "F.Fab")
		)
		(fp_line
			(start 0.6858 0.3048)
			(end 0.1016 0.3048)
			(stroke
				(width 0.1)
				(type default)
			)
			(layer "F.Fab")
		)
		(fp_line
			(start 0.1016 0.3048)
			(end 0.1016 0.2794)
			(stroke
				(width 0.1)
				(type default)
			)
			(layer "F.Fab")
		)
		(fp_line
			(start -0.1016 0.3048)
			(end -0.6858 0.3048)
			(stroke
				(width 0.1)
				(type default)
			)
			(layer "F.Fab")
		)
		(fp_line
			(start -0.6858 0.3048)
			(end -0.6858 -0.3048)
			(stroke
				(width 0.1)
				(type default)
			)
			(layer "F.Fab")
		)
		(pad "1" smd rect
			(at -0.40005 0 270)
			(size 0.4572 0.508)
			(layers "F.Cu" "F.Mask" "F.Paste")
			(net "USB3_CPU0_BMC_RX_HUB2_DN")
		)
		(pad "2" smd rect
			(at 0.40005 0 270)
			(size 0.4572 0.508)
			(layers "F.Cu" "F.Mask" "F.Paste")
			(net "USB3_CPU0_BMC_RX_HUB_C_DN")
		)
	)
	(footprint ""
		(layer "F.Cu")
		(at 277.352252 -123.08967)
		(property "Reference" "R1822"
			(at 0 0 0)
			(layer "F.SilkS")
			(hide yes)
			(effects
				(font
					(size 1.27 1.27)
				)
			)
		)
		(property "Value" ""
			(at 0 0 0)
			(layer "F.Fab")
			(effects
				(font
					(size 1.27 1.27)
				)
			)
		)
		(duplicate_pad_numbers_are_jumpers no)
		(fp_line
			(start -0.7874 -0.4064)
			(end 0.7874 -0.4064)
			(stroke
				(width 0.1524)
				(type default)
			)
			(layer "F.SilkS")
		)
		(fp_line
			(start -0.7874 0.4064)
			(end -0.7874 -0.4064)
			(stroke
				(width 0.1524)
				(type default)
			)
			(layer "F.SilkS")
		)
		(fp_line
			(start 0.7874 -0.4064)
			(end 0.7874 0.4064)
			(stroke
				(width 0.1524)
				(type default)
			)
			(layer "F.SilkS")
		)
		(fp_line
			(start 0.7874 0.4064)
			(end -0.7874 0.4064)
			(stroke
				(width 0.1524)
				(type default)
			)
			(layer "F.SilkS")
		)
		(fp_line
			(start -0.67945 -0.305054)
			(end -0.12065 -0.305054)
			(stroke
				(width 0.1)
				(type default)
			)
			(layer "F.Fab")
		)
		(fp_line
			(start -0.67945 0.3048)
			(end -0.67945 -0.305054)
			(stroke
				(width 0.1)
				(type default)
			)
			(layer "F.Fab")
		)
		(fp_line
			(start -0.12065 -0.305054)
			(end -0.12065 -0.2794)
			(stroke
				(width 0.1)
				(type default)
			)
			(layer "F.Fab")
		)
		(fp_line
			(start -0.12065 -0.2794)
			(end 0.12065 -0.2794)
			(stroke
				(width 0.1)
				(type default)
			)
			(layer "F.Fab")
		)
		(fp_line
			(start -0.12065 0.2794)
			(end -0.12065 0.3048)
			(stroke
				(width 0.1)
				(type default)
			)
			(layer "F.Fab")
		)
		(fp_line
			(start -0.12065 0.3048)
			(end -0.67945 0.3048)
			(stroke
				(width 0.1)
				(type default)
			)
			(layer "F.Fab")
		)
		(fp_line
			(start 0.120396 0.2794)
			(end -0.12065 0.2794)
			(stroke
				(width 0.1)
				(type default)
			)
			(layer "F.Fab")
		)
		(fp_line
			(start 0.120396 0.3048)
			(end 0.120396 0.2794)
			(stroke
				(width 0.1)
				(type default)
			)
			(layer "F.Fab")
		)
		(fp_line
			(start 0.12065 -0.3048)
			(end 0.67945 -0.3048)
			(stroke
				(width 0.1)
				(type default)
			)
			(layer "F.Fab")
		)
		(fp_line
			(start 0.12065 -0.2794)
			(end 0.12065 -0.3048)
			(stroke
				(width 0.1)
				(type default)
			)
			(layer "F.Fab")
		)
		(fp_line
			(start 0.67945 -0.3048)
			(end 0.67945 0.3048)
			(stroke
				(width 0.1)
				(type default)
			)
			(layer "F.Fab")
		)
		(fp_line
			(start 0.67945 0.3048)
			(end 0.120396 0.3048)
			(stroke
				(width 0.1)
				(type default)
			)
			(layer "F.Fab")
		)
		(pad "1" smd circle
			(at -0.40005 0)
			(size 0 0)
			(layers "F.Cu" "F.Mask" "F.Paste")
			(net "P3V3_AUX")
		)
		(pad "2" smd circle
			(at 0.40005 0)
			(size 0 0)
			(layers "F.Cu" "F.Mask" "F.Paste")
			(net "RST_SMB_SWITCH_N")
		)
	)
	(footprint ""
		(layer "F.Cu")
		(at 148.11375 -191.35471 -90)
		(property "Reference" "R3199"
			(at 0 0 270)
			(layer "F.SilkS")
			(hide yes)
			(effects
				(font
					(size 1.27 1.27)
				)
			)
		)
		(property "Value" ""
			(at 0 0 270)
			(layer "F.Fab")
			(effects
				(font
					(size 1.27 1.27)
				)
			)
		)
		(duplicate_pad_numbers_are_jumpers no)
		(fp_line
			(start 0.42291 0.4064)
			(end -0.33909 0.4064)
			(stroke
				(width 0.1524)
				(type default)
			)
			(layer "F.SilkS")
		)
		(fp_line
			(start -0.7874 -0.04445)
			(end -0.7874 -0.4064)
			(stroke
				(width 0.1524)
				(type default)
			)
			(layer "F.SilkS")
		)
		(fp_line
			(start -0.7874 -0.4064)
			(end 0.7874 -0.4064)
			(stroke
				(width 0.1524)
				(type default)
			)
			(layer "F.SilkS")
		)
		(fp_line
			(start 0.7874 -0.4064)
			(end 0.7874 -0.01905)
			(stroke
				(width 0.1524)
				(type default)
			)
			(layer "F.SilkS")
		)
		(fp_line
			(start -0.67945 0.3048)
			(end -0.67945 -0.305054)
			(stroke
				(width 0.1)
				(type default)
			)
			(layer "F.Fab")
		)
		(fp_line
			(start -0.12065 0.3048)
			(end -0.67945 0.3048)
			(stroke
				(width 0.1)
				(type default)
			)
			(layer "F.Fab")
		)
		(fp_line
			(start 0.120396 0.3048)
			(end 0.120396 0.2794)
			(stroke
				(width 0.1)
				(type default)
			)
			(layer "F.Fab")
		)
		(fp_line
			(start 0.67945 0.3048)
			(end 0.120396 0.3048)
			(stroke
				(width 0.1)
				(type default)
			)
			(layer "F.Fab")
		)
		(fp_line
			(start -0.12065 0.2794)
			(end -0.12065 0.3048)
			(stroke
				(width 0.1)
				(type default)
			)
			(layer "F.Fab")
		)
		(fp_line
			(start 0.120396 0.2794)
			(end -0.12065 0.2794)
			(stroke
				(width 0.1)
				(type default)
			)
			(layer "F.Fab")
		)
		(fp_line
			(start -0.12065 -0.2794)
			(end 0.12065 -0.2794)
			(stroke
				(width 0.1)
				(type default)
			)
			(layer "F.Fab")
		)
		(fp_line
			(start 0.12065 -0.2794)
			(end 0.12065 -0.3048)
			(stroke
				(width 0.1)
				(type default)
			)
			(layer "F.Fab")
		)
		(fp_line
			(start 0.12065 -0.3048)
			(end 0.67945 -0.3048)
			(stroke
				(width 0.1)
				(type default)
			)
			(layer "F.Fab")
		)
		(fp_line
			(start 0.67945 -0.3048)
			(end 0.67945 0.3048)
			(stroke
				(width 0.1)
				(type default)
			)
			(layer "F.Fab")
		)
		(fp_line
			(start -0.67945 -0.305054)
			(end -0.12065 -0.305054)
			(stroke
				(width 0.1)
				(type default)
			)
			(layer "F.Fab")
		)
		(fp_line
			(start -0.12065 -0.305054)
			(end -0.12065 -0.2794)
			(stroke
				(width 0.1)
				(type default)
			)
			(layer "F.Fab")
		)
		(pad "1" smd circle
			(at -0.40005 0 270)
			(size 0 0)
			(layers "F.Cu" "F.Mask" "F.Paste")
			(net "CLK_100M_CPU1_CLK04_R_DN")
		)
		(pad "2" smd circle
			(at 0.40005 0 270)
			(size 0 0)
			(layers "F.Cu" "F.Mask" "F.Paste")
			(net "CLK_100M_CPU1_CLK04_DN")
		)
	)
	(footprint ""
		(layer "F.Cu")
		(at 422.180766 -402.7424 -90)
		(property "Reference" "R1082"
			(at 0 0 270)
			(layer "F.SilkS")
			(hide yes)
			(effects
				(font
					(size 1.27 1.27)
				)
			)
		)
		(property "Value" ""
			(at 0 0 270)
			(layer "F.Fab")
			(effects
				(font
					(size 1.27 1.27)
				)
			)
		)
		(duplicate_pad_numbers_are_jumpers no)
		(fp_line
			(start -0.32512 0.175006)
			(end -0.32512 -0.175006)
			(stroke
				(width 0.1)
				(type default)
			)
			(layer "F.Fab")
		)
		(fp_line
			(start 0.32512 0.175006)
			(end -0.32512 0.175006)
			(stroke
				(width 0.1)
				(type default)
			)
			(layer "F.Fab")
		)
		(fp_line
			(start -0.32512 -0.175006)
			(end 0.32512 -0.175006)
			(stroke
				(width 0.1)
				(type default)
			)
			(layer "F.Fab")
		)
		(fp_line
			(start 0.32512 -0.175006)
			(end 0.32512 0.175006)
			(stroke
				(width 0.1)
				(type default)
			)
			(layer "F.Fab")
		)
		(pad "1" smd rect
			(at -0.2667 0 270)
			(size 0.3048 0.381)
			(layers "F.Cu" "F.Mask" "F.Paste")
			(net "RT_CPU0_P2_VQPS")
		)
		(pad "2" smd rect
			(at 0.2667 0 90)
			(size 0.3048 0.381)
			(layers "F.Cu" "F.Mask" "F.Paste")
			(net "GND")
		)
	)
	(footprint ""
		(layer "F.Cu")
		(at 72.635618 -341.04707 180)
		(property "Reference" "PC408_3"
			(at 0 0 180)
			(layer "F.SilkS")
			(hide yes)
			(effects
				(font
					(size 1.27 1.27)
				)
			)
		)
		(property "Value" ""
			(at 0 0 180)
			(layer "F.Fab")
			(effects
				(font
					(size 1.27 1.27)
				)
			)
		)
		(duplicate_pad_numbers_are_jumpers no)
		(fp_line
			(start 0.7874 0.4064)
			(end -0.7874 0.4064)
			(stroke
				(width 0.1524)
				(type default)
			)
			(layer "F.SilkS")
		)
		(fp_line
			(start 0.7874 -0.4064)
			(end 0.7874 0.4064)
			(stroke
				(width 0.1524)
				(type default)
			)
			(layer "F.SilkS")
		)
		(fp_line
			(start -0.7874 0.4064)
			(end -0.7874 -0.4064)
			(stroke
				(width 0.1524)
				(type default)
			)
			(layer "F.SilkS")
		)
		(fp_line
			(start -0.7874 -0.4064)
			(end 0.7874 -0.4064)
			(stroke
				(width 0.1524)
				(type default)
			)
			(layer "F.SilkS")
		)
		(fp_line
			(start 0.67945 0.3048)
			(end 0.120396 0.3048)
			(stroke
				(width 0.1)
				(type default)
			)
			(layer "F.Fab")
		)
		(fp_line
			(start 0.67945 -0.3048)
			(end 0.67945 0.3048)
			(stroke
				(width 0.1)
				(type default)
			)
			(layer "F.Fab")
		)
		(fp_line
			(start 0.12065 -0.2794)
			(end 0.12065 -0.3048)
			(stroke
				(width 0.1)
				(type default)
			)
			(layer "F.Fab")
		)
		(fp_line
			(start 0.12065 -0.3048)
			(end 0.67945 -0.3048)
			(stroke
				(width 0.1)
				(type default)
			)
			(layer "F.Fab")
		)
		(fp_line
			(start 0.120396 0.3048)
			(end 0.120396 0.2794)
			(stroke
				(width 0.1)
				(type default)
			)
			(layer "F.Fab")
		)
		(fp_line
			(start 0.120396 0.2794)
			(end -0.12065 0.2794)
			(stroke
				(width 0.1)
				(type default)
			)
			(layer "F.Fab")
		)
		(fp_line
			(start -0.12065 0.3048)
			(end -0.67945 0.3048)
			(stroke
				(width 0.1)
				(type default)
			)
			(layer "F.Fab")
		)
		(fp_line
			(start -0.12065 0.2794)
			(end -0.12065 0.3048)
			(stroke
				(width 0.1)
				(type default)
			)
			(layer "F.Fab")
		)
		(fp_line
			(start -0.12065 -0.2794)
			(end 0.12065 -0.2794)
			(stroke
				(width 0.1)
				(type default)
			)
			(layer "F.Fab")
		)
		(fp_line
			(start -0.12065 -0.305054)
			(end -0.12065 -0.2794)
			(stroke
				(width 0.1)
				(type default)
			)
			(layer "F.Fab")
		)
		(fp_line
			(start -0.67945 0.3048)
			(end -0.67945 -0.305054)
			(stroke
				(width 0.1)
				(type default)
			)
			(layer "F.Fab")
		)
		(fp_line
			(start -0.67945 -0.305054)
			(end -0.12065 -0.305054)
			(stroke
				(width 0.1)
				(type default)
			)
			(layer "F.Fab")
		)
		(pad "1" smd circle
			(at -0.40005 0 180)
			(size 0 0)
			(layers "F.Cu" "F.Mask" "F.Paste")
			(net "SW_P12V_AUX_PVDDCR_CPU1_P1_FLT")
		)
		(pad "2" smd circle
			(at 0.40005 0 180)
			(size 0 0)
			(layers "F.Cu" "F.Mask" "F.Paste")
			(net "GND")
		)
	)
	(footprint ""
		(layer "F.Cu")
		(at 18.384012 -358.30637 -90)
		(property "Reference" "R6088"
			(at 0 0 270)
			(layer "F.SilkS")
			(hide yes)
			(effects
				(font
					(size 1.27 1.27)
				)
			)
		)
		(property "Value" ""
			(at 0 0 270)
			(layer "F.Fab")
			(effects
				(font
					(size 1.27 1.27)
				)
			)
		)
		(duplicate_pad_numbers_are_jumpers no)
		(fp_line
			(start -0.7874 0.4064)
			(end -0.7874 -0.4064)
			(stroke
				(width 0.1524)
				(type default)
			)
			(layer "F.SilkS")
		)
		(fp_line
			(start 0.7874 0.4064)
			(end -0.7874 0.4064)
			(stroke
				(width 0.1524)
				(type default)
			)
			(layer "F.SilkS")
		)
		(fp_line
			(start -0.7874 -0.4064)
			(end 0.7874 -0.4064)
			(stroke
				(width 0.1524)
				(type default)
			)
			(layer "F.SilkS")
		)
		(fp_line
			(start 0.7874 -0.4064)
			(end 0.7874 0.4064)
			(stroke
				(width 0.1524)
				(type default)
			)
			(layer "F.SilkS")
		)
		(fp_line
			(start -0.67945 0.3048)
			(end -0.67945 -0.305054)
			(stroke
				(width 0.1)
				(type default)
			)
			(layer "F.Fab")
		)
		(fp_line
			(start -0.12065 0.3048)
			(end -0.67945 0.3048)
			(stroke
				(width 0.1)
				(type default)
			)
			(layer "F.Fab")
		)
		(fp_line
			(start 0.120396 0.3048)
			(end 0.120396 0.2794)
			(stroke
				(width 0.1)
				(type default)
			)
			(layer "F.Fab")
		)
		(fp_line
			(start 0.67945 0.3048)
			(end 0.120396 0.3048)
			(stroke
				(width 0.1)
				(type default)
			)
			(layer "F.Fab")
		)
		(fp_line
			(start -0.12065 0.2794)
			(end -0.12065 0.3048)
			(stroke
				(width 0.1)
				(type default)
			)
			(layer "F.Fab")
		)
		(fp_line
			(start 0.120396 0.2794)
			(end -0.12065 0.2794)
			(stroke
				(width 0.1)
				(type default)
			)
			(layer "F.Fab")
		)
		(fp_line
			(start -0.12065 -0.2794)
			(end 0.12065 -0.2794)
			(stroke
				(width 0.1)
				(type default)
			)
			(layer "F.Fab")
		)
		(fp_line
			(start 0.12065 -0.2794)
			(end 0.12065 -0.3048)
			(stroke
				(width 0.1)
				(type default)
			)
			(layer "F.Fab")
		)
		(fp_line
			(start 0.12065 -0.3048)
			(end 0.67945 -0.3048)
			(stroke
				(width 0.1)
				(type default)
			)
			(layer "F.Fab")
		)
		(fp_line
			(start 0.67945 -0.3048)
			(end 0.67945 0.3048)
			(stroke
				(width 0.1)
				(type default)
			)
			(layer "F.Fab")
		)
		(fp_line
			(start -0.67945 -0.305054)
			(end -0.12065 -0.305054)
			(stroke
				(width 0.1)
				(type default)
			)
			(layer "F.Fab")
		)
		(fp_line
			(start -0.12065 -0.305054)
			(end -0.12065 -0.2794)
			(stroke
				(width 0.1)
				(type default)
			)
			(layer "F.Fab")
		)
		(pad "1" smd circle
			(at -0.40005 0 270)
			(size 0 0)
			(layers "F.Cu" "F.Mask" "F.Paste")
			(net "PVDDIO_P1_EN_R")
		)
		(pad "2" smd circle
			(at 0.40005 0 270)
			(size 0 0)
			(layers "F.Cu" "F.Mask" "F.Paste")
			(net "GND")
		)
	)
	(footprint ""
		(layer "F.Cu")
		(at 143.531844 -373.03583 -90)
		(property "Reference" "C768"
			(at 0 0 270)
			(layer "F.SilkS")
			(hide yes)
			(effects
				(font
					(size 1.27 1.27)
				)
			)
		)
		(property "Value" ""
			(at 0 0 270)
			(layer "F.Fab")
			(effects
				(font
					(size 1.27 1.27)
				)
			)
		)
		(duplicate_pad_numbers_are_jumpers no)
		(fp_line
			(start -0.299974 0.150114)
			(end -0.299974 -0.150114)
			(stroke
				(width 0.1)
				(type default)
			)
			(layer "F.Fab")
		)
		(fp_line
			(start 0.299974 0.150114)
			(end -0.299974 0.150114)
			(stroke
				(width 0.1)
				(type default)
			)
			(layer "F.Fab")
		)
		(fp_line
			(start -0.299974 -0.150114)
			(end 0.299974 -0.150114)
			(stroke
				(width 0.1)
				(type default)
			)
			(layer "F.Fab")
		)
		(fp_line
			(start 0.299974 -0.150114)
			(end 0.299974 0.150114)
			(stroke
				(width 0.1)
				(type default)
			)
			(layer "F.Fab")
		)
		(pad "1" smd rect
			(at -0.2667 0 270)
			(size 0.3048 0.381)
			(layers "F.Cu" "F.Mask" "F.Paste")
			(net "P5E_CPU1_P2_TX_C_DN<2>")
		)
		(pad "2" smd rect
			(at 0.2667 0 270)
			(size 0.3048 0.381)
			(layers "F.Cu" "F.Mask" "F.Paste")
			(net "P5E_CPU1_P2_TX_DN<2>")
		)
	)
	(footprint ""
		(layer "F.Cu")
		(at 236.003338 -416.997642)
		(property "Reference" "FS1"
			(at -6.4262 -2.64033 0)
			(unlocked yes)
			(layer "F.SilkS")
			(effects
				(font
					(size 0.7874 0.5842)
					(thickness 0.1524)
				)
				(justify left)
			)
		)
		(property "Value" ""
			(at 0 0 0)
			(layer "F.Fab")
			(effects
				(font
					(size 1.27 1.27)
				)
			)
		)
		(duplicate_pad_numbers_are_jumpers no)
		(fp_line
			(start -6.427724 -1.8415)
			(end -6.427724 1.8415)
			(stroke
				(width 0.1524)
				(type default)
			)
			(layer "F.SilkS")
		)
		(fp_line
			(start -6.427724 1.8415)
			(end 6.427724 1.8415)
			(stroke
				(width 0.1524)
				(type default)
			)
			(layer "F.SilkS")
		)
		(fp_line
			(start 6.427724 -1.8415)
			(end -6.427724 -1.8415)
			(stroke
				(width 0.1524)
				(type default)
			)
			(layer "F.SilkS")
		)
		(fp_line
			(start 6.427724 1.8415)
			(end 6.427724 -1.8415)
			(stroke
				(width 0.1524)
				(type default)
			)
			(layer "F.SilkS")
		)
		(fp_line
			(start -5.225034 -1.610106)
			(end 5.225034 -1.610106)
			(stroke
				(width 0.1)
				(type default)
			)
			(layer "F.Fab")
		)
		(fp_line
			(start -5.225034 1.610106)
			(end -5.225034 -1.610106)
			(stroke
				(width 0.1)
				(type default)
			)
			(layer "F.Fab")
		)
		(fp_line
			(start 5.225034 -1.610106)
			(end 5.225034 1.610106)
			(stroke
				(width 0.1)
				(type default)
			)
			(layer "F.Fab")
		)
		(fp_line
			(start 5.225034 1.610106)
			(end -5.225034 1.610106)
			(stroke
				(width 0.1)
				(type default)
			)
			(layer "F.Fab")
		)
		(pad "1" smd rect
			(at -4.675124 0)
			(size 3.2512 3.429)
			(layers "F.Cu" "F.Mask" "F.Paste")
			(net "P12V_PSU")
		)
		(pad "2" smd rect
			(at 4.675124 0)
			(size 3.2512 3.429)
			(layers "F.Cu" "F.Mask" "F.Paste")
			(net "P12V_PSU_FUSE")
		)
	)
)
